# BASEBOARD_FAB2 (Tioga Pass) — schematic parts with pin connectivity, parts 4650–4650 of 4751; source: Cadence DE-HDL packaged netlist (pstxprt.dat, pstxnet.dat, pstchip.dat)

U2D1  SKX_EXT_B  IC  pkg BGA1  page 55  (pins 1-338 of 3647)
  A4  RSVD(304)  BI  = TP_CPU1_RSVD_304
  A6  RSVD(303)  BI  = TP_CPU1_RSVD_303
  A8  CD_VPP(3)  POWER  = PVPP_GHJ
  A10  CD_VPP(2)  POWER  = PVPP_GHJ
  A12  CD_VPP(1)  POWER  = PVPP_GHJ
  A14  RSVD(302)  BI  = P1V8_MCP_CPU1
  A16  RSVD(301)  BI  = P1V8_MCP_CPU1
  A24  RSVD(300)  BI  = TP_CPU1_RSVD_300
  A26  VSS(1185)  GROUND  = GND
  A28  DDR1_DQS_DN(15)  BI  = M_H_DQS_DN<15>
  A30  VSS(1184)  GROUND  = GND
  A32  VSS(1183)  GROUND  = GND
  A34  DDR1_DQS_DN(14)  BI  = M_H_DQS_DN<14>
  A36  VSS(1182)  GROUND  = GND
  A38  VSS(1181)  GROUND  = GND
  A40  DDR0_DQS_DN(13)  BI  = M_G_DQS_DN<13>
  A42  VSS(1252)  GROUND  = GND
  AA2  UPI0_TX_DP(4)  OUT  = UPI_CPU1_CPU0_P0P0_DP<4>
  AA4  VSS(935)  GROUND  = GND
  AA6  UPI0_RX_DP(2)  IN  = UPI_CPU0_CPU1_P0P0_DP<2>
  AA8  UPI0_RX_DN(1)  IN  = UPI_CPU0_CPU1_P0P0_DN<1>
  AA10  VCCIO(45)  POWER  = PVCCIO_CPU1
  AA12  BPM_N(4)  BI  = TP_XDP_CPU1_OBSDATA_B2_MBP4_N
  AA14  TCK  IN  = XDP_CPU_TCK0
  AA16  VSS(934)  GROUND  = GND
  AA18  VSS(933)  GROUND  = GND
  AA20  UPI1_RX_DP(19)  IN  = UPI_CPU0_CPU1_P1P1_DN<19>
  AA22  VSS(932)  GROUND  = GND
  AA24  VSS(931)  GROUND  = GND
  AA26  DDR1_DQ(63)  BI  = M_H_DQ<63>
  AA28  DDR1_DQ(57)  BI  = M_H_DQ<57>
  AA30  VSS(930)  GROUND  = GND
  AA32  DDR2_DQ(47)  BI  = M_J_DQ<47>
  AA34  DDR2_DQ(41)  BI  = M_J_DQ<41>
  AA36  VSS(929)  GROUND  = GND
  AA38  DDR2_DQ(39)  BI  = M_J_DQ<39>
  AA40  DDR2_DQ(33)  BI  = M_J_DQ<33>
  AA42  VSS(928)  GROUND  = GND
  AA46  DDR2_CS_N(3)  OUT  = M_J_CS_N<3>
  AA48  DDR2_ODT(1)  OUT  = M_J_ODT<1>
  AA50  DDR2_ODT(0)  OUT  = M_J_ODT<0>
  AA52  DDR2_MA(16)  OUT  = M_J_MA<16>
  AA54  DDR2_CLK_DN(0)  OUT  = M_J_CLK_DN<0>
  AA56  DDR2_CLK_DN(2)  OUT  = M_J_CLK_DN<2>
  AA58  DDR2_MA(4)  OUT  = M_J_MA<4>
  AA60  DDR2_BG(0)  OUT  = M_J_BG<0>
  AA62  DDR2_CKE(0)  OUT  = M_J_CKE<0>
  AA64  VSS(927)  GROUND  = GND
  AA66  VSS(926)  GROUND  = GND
  AA68  VSS(925)  GROUND  = GND
  AA70  DDR2_DQ(17)  BI  = M_J_DQ<17>
  AA72  DDR2_DQ(20)  BI  = M_J_DQ<20>
  AA74  DDR2_DQS_DN(1)  BI  = M_J_DQS_DN<1>
  AA76  VSS(924)  GROUND  = GND
  AA78  VSS(923)  GROUND  = GND
  AA80  VSS(922)  GROUND  = GND
  AA82  VSS(921)  GROUND  = GND
  AA84  DDR0_DQ(13)  BI  = M_G_DQ<13>
  AA86  DDR0_DQ(12)  BI  = M_G_DQ<12>
  AB1  VSS(920)  GROUND  = GND
  AB3  UPI0_TX_DN(4)  OUT  = UPI_CPU1_CPU0_P0P0_DN<4>
  AB5  VSS(919)  GROUND  = GND
  AB7  UPI0_RX_DN(2)  IN  = UPI_CPU0_CPU1_P0P0_DN<2>
  AB9  UPI0_RX_DP(0)  IN  = UPI_CPU0_CPU1_P0P0_DN<0>
  AB11  VSS(918)  GROUND  = GND
  AB13  SKTOCC_N  OUT  = FM_CPU1_SKTOCC_LVT3_N
  AB15  THERMTRIP_N  OUT  = H_CPU1_THERMTRIP_G_N
  AB17  PROCDIS_N  IN  = TP_CPU1_PROC_DIS_G_N
  AB19  UPI1_RX_DN(19)  IN  = UPI_CPU0_CPU1_P1P1_DP<19>
  AB21  VSS(917)  GROUND  = GND
  AB23  VSS(916)  GROUND  = GND
  AB25  VSS(915)  GROUND  = GND
  AB27  DDR1_DQS_DN(7)  BI  = M_H_DQS_DN<7>
  AB29  VSS(914)  GROUND  = GND
  AB31  VSS(913)  GROUND  = GND
  AB33  DDR2_DQS_DN(5)  BI  = M_J_DQS_DN<5>
  AB35  VSS(912)  GROUND  = GND
  AB37  VSS(911)  GROUND  = GND
  AB39  DDR2_DQS_DN(4)  BI  = M_J_DQS_DN<4>
  AB41  VSS(910)  GROUND  = GND
  AB43  DDR012_RCOMP(1)  BI  = A_CPU1_GHJ_RCOMP1
  AB45  DDR2_CID(2)  OUT  = M_J_C<2>
  AB47  DDR2_ODT(3)  OUT  = M_J_ODT<3>
  AB49  DDR2_CS_N(1)  OUT  = M_J_CS_N<1>
  AB51  DDR2_CS_N(4)  OUT  = M_J_CS_N<4>
  AB53  DDR2_MA(0)  OUT  = M_J_MA<0>
  AB55  DDR2_CLK_DP(0)  OUT  = M_J_CLK_DP<0>
  AB57  DDR2_CLK_DP(2)  OUT  = M_J_CLK_DP<2>
  AB59  DDR2_MA(6)  OUT  = M_J_MA<6>
  AB61  DDR2_ACT_N  OUT  = M_J_ACT_N
  AB63  DDR2_CKE(3)  OUT  = M_J_CKE<3>
  AB65  VSS(909)  GROUND  = GND
  AB67  DDR0_DQS_DN(17)  BI  = M_G_DQS_DN<17>
  AB69  VSS(908)  GROUND  = GND
  AB71  DDR2_DQ(21)  BI  = M_J_DQ<21>
  AB73  VSS(907)  GROUND  = GND
  AB75  DDR2_DQS_DP(1)  BI  = M_J_DQS_DP<1>
  AB77  DDR2_DQ(14)  BI  = M_J_DQ<14>
  AB79  VSS(906)  GROUND  = GND
  AB81  DDR1_DQ(11)  BI  = M_H_DQ<11>
  AB83  VSS(905)  GROUND  = GND
  AB85  VSS(904)  GROUND  = GND
  AC2  UPI0_TX_DN(5)  OUT  = UPI_CPU1_CPU0_P0P0_DP<5>
  AC4  VCCIO(43)  POWER  = PVCCIO_CPU1
  AC6  UPI0_RX_DP(3)  IN  = UPI_CPU0_CPU1_P0P0_DN<3>
  AC8  UPI0_RX_DP(1)  IN  = UPI_CPU0_CPU1_P0P0_DP<1>
  AC10  UPI0_RX_DN(0)  IN  = UPI_CPU0_CPU1_P0P0_DP<0>
  AC12  BPM_N(7)  BI  = XDP_CPU_OBSFN_B1_MBP7_N
  AC14  TDI  IN  = XDP_CPU1_TDI
  AC16  PROCHOT_N  BI  = H_CPU1_PROCHOT_G_N
  AC18  VSS(903)  GROUND  = GND
  AC20  VCCIO(44)  POWER  = PVCCIO_CPU1
  AC22  VSS(902)  GROUND  = GND
  AC24  DDR2_DQS_DN(16)  BI  = M_J_DQS_DN<16>
  AC26  VSS(901)  GROUND  = GND
  AC28  VSS(900)  GROUND  = GND
  AC30  DDR2_DQS_DN(15)  BI  = M_J_DQS_DN<15>
  AC32  VSS(899)  GROUND  = GND
  AC34  VSS(898)  GROUND  = GND
  AC36  VCCIO(97)  POWER  = PVCCIO_CPU1
  AC38  VSS(897)  GROUND  = GND
  AC40  VSS(896)  GROUND  = GND
  AC42  DDR012_RCOMP(2)  BI  = A_CPU1_GHJ_RCOMP2
  AC46  DDR2_MA(17)  OUT  = M_J_MA<17>
  AC48  VSS(733)  GROUND  = GND
  AC50  VSS(767)  GROUND  = GND
  AC52  VSS(858)  GROUND  = GND
  AC54  VSS(869)  GROUND  = GND
  AC56  VSS(964)  GROUND  = GND
  AC58  VSS(1186)  GROUND  = GND
  AC60  VSS(1187)  GROUND  = GND
  AC62  VSS(1188)  GROUND  = GND
  AC64  VSS(895)  GROUND  = GND
  AC66  DDR0_ECC(6)  BI  = M_G_ECC<6>
  AC68  DDR0_ECC(0)  BI  = M_G_ECC<0>
  AC70  VSS(894)  GROUND  = GND
  AC72  VSS(893)  GROUND  = GND
  AC74  DDR2_DQ(9)  BI  = M_J_DQ<9>
  AC76  DDR2_DQS_DP(10)  BI  = M_J_DQS_DP<10>
  AC78  VSS(892)  GROUND  = GND
  AC80  DDR1_DQ(15)  BI  = M_H_DQ<15>
  AC82  DDR1_DQ(10)  BI  = M_H_DQ<10>
  AC84  VSS(891)  GROUND  = GND
  AC86  VSS(890)  GROUND  = GND
  AD1  UPI0_TX_DP(5)  OUT  = UPI_CPU1_CPU0_P0P0_DN<5>
  AD3  VSS(889)  GROUND  = GND
  AD5  UPI0_RX_DN(3)  IN  = UPI_CPU0_CPU1_P0P0_DP<3>
  AD7  VSS(888)  GROUND  = GND
  AD9  VSS(887)  GROUND  = GND
  AD11  VSS(886)  GROUND  = GND
  AD13  VSS(885)  GROUND  = GND
  AD15  VSS(884)  GROUND  = GND
  AD17  DDR345_SPDSDA  BI  = SMB_DDR_KLM_SDA_G_R
  AD19  VSS(883)  GROUND  = GND
  AD21  VSS(882)  GROUND  = GND
  AD23  DDR2_DQ(62)  BI  = M_J_DQ<62>
  AD25  DDR2_DQ(56)  BI  = M_J_DQ<56>
  AD27  VSS(881)  GROUND  = GND
  AD29  DDR2_DQ(54)  BI  = M_J_DQ<54>
  AD31  DDR2_DQ(48)  BI  = M_J_DQ<48>
  AD33  VSS(880)  GROUND  = GND
  AD35  VCCIO(99)  POWER  = PVCCIO_CPU1
  AD37  VCCIO(96)  POWER  = PVCCIO_CPU1
  AD39  VSS(879)  GROUND  = GND
  AD41  VSENSEPMAX  POWER  = VSENSE_PMAX_CPU1
  AD43  VSS(878)  GROUND  = GND
  AD45  VCCD012(43)  POWER  = PVDDQ_GHJ
  AD47  RSVD(254)  BI  = TP_CPU1_RSVD_254
  AD49  RSVD(253)  BI  = TP_CPU1_RSVD_253
  AD51  RSVD(252)  BI  = TP_CPU1_RSVD_252
  AD53  DDR2_MA(13)  OUT  = M_J_MA<13>
  AD55  DDR2_MA(10)  OUT  = M_J_MA<10>
  AD57  DDR2_MA(2)  OUT  = M_J_MA<2>
  AD59  DDR2_MA(8)  OUT  = M_J_MA<8>
  AD61  DDR2_ALERT_N  IN  = M_J_ALERT_N
  AD63  DDR2_CKE(1)  OUT  = M_J_CKE<1>
  AD65  DDR0_ECC(2)  BI  = M_G_ECC<2>
  AD67  DDR0_DQS_DP(17)  BI  = M_G_DQS_DP<17>
  AD69  DDR0_ECC(4)  BI  = M_G_ECC<4>
  AD71  VSS(877)  GROUND  = GND
  AD73  VSS(876)  GROUND  = GND
  AD75  VSS(875)  GROUND  = GND
  AD77  DDR2_DQS_DN(10)  BI  = M_J_DQS_DN<10>
  AD79  DDR1_DQS_DN(1)  BI  = M_H_DQS_DN<1>
  AD81  VSS(874)  GROUND  = GND
  AD83  VSS(873)  GROUND  = GND
  AD85  VSS(872)  GROUND  = GND
  AE2  UPI0_TX_DN(7)  OUT  = UPI_CPU1_CPU0_P0P0_DN<7>
  AE4  VSS(871)  GROUND  = GND
  AE6  UPI0_RX_DN(4)  IN  = UPI_CPU0_CPU1_P0P0_DP<4>
  AE8  VSS(870)  GROUND  = GND
  AE10  VCCIO(1)  POWER  = PVCCIO_CPU1
  AE12  BPM_N(6)  BI  = XDP_CPU_OBSFN_B0_MBP6_N
  AE14  TDO  OUT  = XDP_CPU1_TDO
  AE16  VSS(868)  GROUND  = GND
  AE18  DDR345_SPDSCL  BI  = SMB_DDR_KLM_SCL_G_R
  AE20  LEGACY_SKT  IN  = PU_CPU1_LEGACY_SKT
  AE22  DDR2_DQ(58)  BI  = M_J_DQ<58>
  AE24  DDR2_DQS_DP(16)  BI  = M_J_DQS_DP<16>
  AE26  DDR2_DQ(60)  BI  = M_J_DQ<60>
  AE28  DDR2_DQ(50)  BI  = M_J_DQ<50>
  AE30  DDR2_DQS_DP(15)  BI  = M_J_DQS_DP<15>
  AE32  DDR2_DQ(52)  BI  = M_J_DQ<52>
  AE34  VCCIO(100)  POWER  = PVCCIO_CPU1
  AE36  VCCIO(95)  POWER  = PVCCIO_CPU1
  AE38  VSS(867)  GROUND  = GND
  AE40  VSS(866)  GROUND  = GND
  AE42  VSS(865)  GROUND  = GND
  AE46  RSVD(251)  BI  = TP_CPU1_RSVD_251
  AE48  RSVD(250)  BI  = TP_CPU1_RSVD_250
  AE50  RSVD(249)  BI  = TP_CPU1_RSVD_249
  AE52  RSVD(248)  BI  = TP_CPU1_RSVD_248
  AE54  DDR2_MA(15)  OUT  = M_J_MA<15>
  AE56  DDR2_BA(1)  OUT  = M_J_BA<1>
  AE58  DDR2_MA(1)  OUT  = M_J_MA<1>
  AE60  DDR2_MA(7)  OUT  = M_J_MA<7>
  AE62  DDR2_BG(1)  OUT  = M_J_BG<1>
  AE64  VSS(864)  GROUND  = GND
  AE66  VSS(863)  GROUND  = GND
  AE68  VSS(862)  GROUND  = GND
  AE70  VSS(861)  GROUND  = GND
  AE72  RSVD(247)  BI  = TP_CPU1_RSVD_247
  AE74  DDR2_DQ(13)  BI  = M_J_DQ<13>
  AE76  DDR2_DQ(8)  BI  = M_J_DQ<8>
  AE78  VSS(860)  GROUND  = GND
  AE80  DDR1_DQS_DP(1)  BI  = M_H_DQS_DP<1>
  AE82  DDR1_DQ(14)  BI  = M_H_DQ<14>
  AE84  DDR0_DQ(3)  BI  = M_G_DQ<3>
  AE86  DDR0_DQ(2)  BI  = M_G_DQ<2>
  AF1  VSS(859)  GROUND  = GND
  AF3  UPI0_TX_DP(6)  OUT  = UPI_CPU1_CPU0_P0P0_DP<6>
  AF5  VCCIO(2)  POWER  = PVCCIO_CPU1
  AF7  UPI0_RX_DP(5)  IN  = UPI_CPU0_CPU1_P0P0_DN<5>
  AF9  VSS(857)  GROUND  = GND
  AF11  BPM_N(3)  BI  = TP_XDP_CPU1_OBSDATA_B1_MBP3_N
  AF13  MEM_HOT_C345_N  BI  = H_CPU1_MEMKLM_MEMHOT_G_N
  AF15  PM_FAST_WAKE_N  BI  = H_CPU1_FAST_WAKE_N
  AF17  DDR012_SPDSDA  BI  = SMB_DDR_GHJ_SDA_G_R
  AF19  RSVD(246)  BI  = TP_CPU1_RSVD_246
  AF21  VSS(856)  GROUND  = GND
  AF23  VSS(855)  GROUND  = GND
  AF25  VSS(854)  GROUND  = GND
  AF27  VSS(853)  GROUND  = GND
  AF29  VSS(852)  GROUND  = GND
  AF31  VSS(851)  GROUND  = GND
  AF33  VSS(850)  GROUND  = GND
  AF35  VCCIO(98)  POWER  = PVCCIO_CPU1
  AF37  VSS(849)  GROUND  = GND
  AF39  VSS(848)  GROUND  = GND
  AF41  VSS(847)  GROUND  = GND
  AF43  VCCIN(267)  POWER  = PVCCIN_CPU1
  AF45  TEST_1  BI  = PD_CPU1_RSVD_TEST_1
  AF47  RSVD(245)  BI  = TP_CPU1_RSVD_245
  AF49  RSVD(244)  BI  = TP_CPU1_RSVD_244
  AF51  RSVD(243)  BI  = TP_CPU1_RSVD_243
  AF53  RSVD(242)  BI  = TP_CPU1_RSVD_242
  AF55  VCCD012(44)  POWER  = PVDDQ_GHJ
  AF57  VCCD012(45)  POWER  = PVDDQ_GHJ
  AF59  VCCD012(46)  POWER  = PVDDQ_GHJ
  AF61  VCCD012(47)  POWER  = PVDDQ_GHJ
  AF63  VCCD012(48)  POWER  = PVDDQ_GHJ
  AF65  DDR0_ECC(3)  BI  = M_G_ECC<3>
  AF67  DDR0_DQS_DP(8)  BI  = M_G_DQS_DP<8>
  AF69  DDR0_ECC(5)  BI  = M_G_ECC<5>
  AF71  RSVD(241)  BI  = TP_CPU1_RSVD_241
  AF73  VSS(846)  GROUND  = GND
  AF75  DDR2_DQ(12)  BI  = M_J_DQ<12>
  AF77  VSS(845)  GROUND  = GND
  AF79  DDR1_DQ(9)  BI  = M_H_DQ<9>
  AF81  DDR1_DQS_DP(10)  BI  = M_H_DQS_DP<10>
  AF83  VSS(844)  GROUND  = GND
  AF85  VSS(843)  GROUND  = GND
  AG2  UPI0_TX_DP(7)  OUT  = UPI_CPU1_CPU0_P0P0_DP<7>
  AG4  UPI0_TX_DN(6)  OUT  = UPI_CPU1_CPU0_P0P0_DN<6>
  AG6  UPI0_RX_DP(4)  IN  = UPI_CPU0_CPU1_P0P0_DN<4>
  AG8  UPI0_RX_DN(5)  IN  = UPI_CPU0_CPU1_P0P0_DP<5>
  AG10  BPM_N(2)  BI  = TP_XDP_CPU1_OBSDATA_B0_MBP2_N
  AG12  VSS(842)  GROUND  = GND
  AG14  VSS(841)  GROUND  = GND
  AG16  PRDY_N  OUT  = XDP_CPU_PRDY_N
  AG18  VSS(840)  GROUND  = GND
  AG20  RSVD(240)  BI  = TP_CPU1_RSVD_240
  AG22  DDR2_DQ(59)  BI  = M_J_DQ<59>
  AG24  DDR2_DQS_DP(7)  BI  = M_J_DQS_DP<7>
  AG26  DDR2_DQ(61)  BI  = M_J_DQ<61>
  AG28  DDR2_DQ(51)  BI  = M_J_DQ<51>
  AG30  DDR2_DQS_DP(6)  BI  = M_J_DQS_DP<6>
  AG32  DDR2_DQ(53)  BI  = M_J_DQ<53>
  AG34  VCCIO(101)  POWER  = PVCCIO_CPU1
  AG36  VSS(839)  GROUND  = GND
  AG38  VCCIN(266)  POWER  = PVCCIN_CPU1
  AG40  VCCIN(265)  POWER  = PVCCIN_CPU1
  AG42  VCCIN(264)  POWER  = PVCCIN_CPU1
  AG46  TEST_2  BI  = PD_CPU1_RSVD_TEST_2
  AG48  RSVD(239)  BI  = TP_CPU1_RSVD_239
  AG50  RSVD(238)  BI  = TP_CPU1_RSVD_238
  AG52  RSVD(237)  BI  = TP_CPU1_RSVD_237
  AG54  RSVD(236)  BI  = TP_CPU1_RSVD_236
  AG56  RSVD(235)  BI  = TP_CPU1_RSVD_235
  AG58  DDR2_MA(9)  OUT  = M_J_MA<9>
  AG60  DDR2_MA(11)  OUT  = M_J_MA<11>
  AG62  DDR2_MA(12)  OUT  = M_J_MA<12>
  AG64  VSS(838)  GROUND  = GND
  AG66  DDR0_ECC(7)  BI  = M_G_ECC<7>
  AG68  DDR0_ECC(1)  BI  = M_G_ECC<1>
  AG70  VSS(837)  GROUND  = GND
  AG72  RSVD(234)  BI  = TP_CPU1_RSVD_234
  AG74  VSS(836)  GROUND  = GND
  AG76  VSS(835)  GROUND  = GND
  AG78  VSS(834)  GROUND  = GND
  AG80  VSS(833)  GROUND  = GND
  AG82  DDR1_DQS_DN(10)  BI  = M_H_DQS_DN<10>
  AG84  DDR0_DQ(7)  BI  = M_G_DQ<7>
  AG86  DDR0_DQ(6)  BI  = M_G_DQ<6>
  AH1  VSS(832)  GROUND  = GND
  AH3  UPI0_TX_DN(8)  OUT  = UPI_CPU1_CPU0_P0P0_DP<8>
  AH5  VSS(831)  GROUND  = GND
  AH7  UPI0_RX_DP(6)  IN  = UPI_CPU0_CPU1_P0P0_DN<6>
  AH9  VCCIO(42)  POWER  = PVCCIO_CPU1
  AH11  BPM_N(1)  BI  = XDP_CPU_MBP1_N
  AH13  MEM_HOT_C012_N  BI  = H_CPU1_MEMGHJ_MEMHOT_G_N
  AH15  RSVD(233)  BI  = TP_CPU1_RSVD_233
  AH19  RSVD(232)  BI  = TP_CPU1_RSVD_232
  AH21  VSS(830)  GROUND  = GND
  AH23  DDR2_DQ(63)  BI  = M_J_DQ<63>
  AH25  DDR2_DQ(57)  BI  = M_J_DQ<57>
  AH27  VSS(829)  GROUND  = GND
  AH29  DDR2_DQ(55)  BI  = M_J_DQ<55>
  AH31  DDR2_DQ(49)  BI  = M_J_DQ<49>
  AH33  VSS(828)  GROUND  = GND
  AH35  VSS(827)  GROUND  = GND
  AH37  VCCIN(263)  POWER  = PVCCIN_CPU1
  AH39  VCCIN(262)  POWER  = PVCCIN_CPU1
  AH41  VCCIN(261)  POWER  = PVCCIN_CPU1
  AH45  VSS(826)  GROUND  = GND
  AH47  VSS(825)  GROUND  = GND
  AH49  VSS(824)  GROUND  = GND
  AH51  VSS(823)  GROUND  = GND
